(kicad_pcb
	(version 20260206)
	(generator "pcbnew")
	(generator_version "10.0")
	(general
		(thickness 1.6)
		(legacy_teardrops no)
	)
	(paper "A4")
	(title_block
		(title "01162023_DA0F0TEBIF0_F0T_Expander_BD_F_brd_V02_OCP.brd")
		(comment 1 "Grand Teton / footprints 8871-8878 of 9728")
	)
	(layers
		(0 "F.Cu" signal "TOP")
		(4 "In1.Cu" signal "GND")
		(6 "In2.Cu" signal "VCC")
		(8 "In3.Cu" signal "VCC1")
		(10 "In4.Cu" signal "GND1")
		(12 "In5.Cu" signal "IN1")
		(14 "In6.Cu" signal "GND2")
		(16 "In7.Cu" signal "IN2")
		(18 "In8.Cu" signal "GND3")
		(20 "In9.Cu" signal "IN3")
		(22 "In10.Cu" signal "GND4")
		(24 "In11.Cu" signal "IN4")
		(26 "In12.Cu" signal "GND5")
		(28 "In13.Cu" signal "IN5")
		(30 "In14.Cu" signal "GND6")
		(32 "In15.Cu" signal "IN6")
		(34 "In16.Cu" signal "GND7")
		(2 "B.Cu" signal "BOTTOM")
		(9 "F.Adhes" user "F.Adhesive")
		(11 "B.Adhes" user "B.Adhesive")
		(13 "F.Paste" user "Package Geometry/Pastemask Top")
		(15 "B.Paste" user "Package Geometry/Pastemask Bottom")
		(5 "F.SilkS" user "Ref Des/Silkscreen Top")
		(7 "B.SilkS" user "Ref Des/Silkscreen Bottom")
		(1 "F.Mask" user "Board Geometry/Soldermask Top")
		(3 "B.Mask" user "Board Geometry/Soldermask Bottom")
		(17 "Dwgs.User" user "User.Drawings")
		(19 "Cmts.User" user "User.Comments")
		(21 "Eco1.User" user "User.Eco1")
		(23 "Eco2.User" user "User.Eco2")
		(25 "Edge.Cuts" user "Board Geometry/Outline")
		(27 "Margin" user)
		(31 "F.CrtYd" user "Package Geometry/Place Bound Top")
		(29 "B.CrtYd" user "Package Geometry/Place Bound Bottom")
		(35 "F.Fab" user "Ref Des/Assembly Top")
		(33 "B.Fab" user "Ref Des/Assembly Bottom")
	)
	(footprint ""
		(layer "B.Cu")
		(at 107.621832 -347.210888)
		(property "Reference" "R6369"
			(at 0 0 0)
			(layer "B.SilkS")
			(hide yes)
			(effects
				(font
					(size 1.27 1.27)
				)
				(justify mirror)
			)
		)
		(property "Value" ""
			(at 0 0 0)
			(layer "B.Fab")
			(effects
				(font
					(size 1.27 1.27)
				)
				(justify mirror)
			)
		)
		(duplicate_pad_numbers_are_jumpers no)
		(fp_line
			(start -0.7874 -0.4064)
			(end -0.7874 0.4064)
			(stroke
				(width 0.1524)
				(type default)
			)
			(layer "B.SilkS")
		)
		(fp_line
			(start -0.7874 0.4064)
			(end 0.7874 0.4064)
			(stroke
				(width 0.1524)
				(type default)
			)
			(layer "B.SilkS")
		)
		(fp_line
			(start 0.7874 -0.4064)
			(end -0.7874 -0.4064)
			(stroke
				(width 0.1524)
				(type default)
			)
			(layer "B.SilkS")
		)
		(fp_line
			(start 0.7874 0.4064)
			(end 0.7874 -0.4064)
			(stroke
				(width 0.1524)
				(type default)
			)
			(layer "B.SilkS")
		)
		(fp_line
			(start -0.67945 -0.3048)
			(end -0.67945 0.3048)
			(stroke
				(width 0.1)
				(type default)
			)
			(layer "B.Fab")
		)
		(fp_line
			(start -0.67945 0.3048)
			(end -0.120396 0.3048)
			(stroke
				(width 0.1)
				(type default)
			)
			(layer "B.Fab")
		)
		(fp_line
			(start -0.12065 -0.3048)
			(end -0.67945 -0.3048)
			(stroke
				(width 0.1)
				(type default)
			)
			(layer "B.Fab")
		)
		(fp_line
			(start -0.12065 -0.2794)
			(end -0.12065 -0.3048)
			(stroke
				(width 0.1)
				(type default)
			)
			(layer "B.Fab")
		)
		(fp_line
			(start -0.120396 0.2794)
			(end 0.12065 0.2794)
			(stroke
				(width 0.1)
				(type default)
			)
			(layer "B.Fab")
		)
		(fp_line
			(start -0.120396 0.3048)
			(end -0.120396 0.2794)
			(stroke
				(width 0.1)
				(type default)
			)
			(layer "B.Fab")
		)
		(fp_line
			(start 0.12065 -0.305054)
			(end 0.12065 -0.2794)
			(stroke
				(width 0.1)
				(type default)
			)
			(layer "B.Fab")
		)
		(fp_line
			(start 0.12065 -0.2794)
			(end -0.12065 -0.2794)
			(stroke
				(width 0.1)
				(type default)
			)
			(layer "B.Fab")
		)
		(fp_line
			(start 0.12065 0.2794)
			(end 0.12065 0.3048)
			(stroke
				(width 0.1)
				(type default)
			)
			(layer "B.Fab")
		)
		(fp_line
			(start 0.12065 0.3048)
			(end 0.67945 0.3048)
			(stroke
				(width 0.1)
				(type default)
			)
			(layer "B.Fab")
		)
		(fp_line
			(start 0.67945 -0.305054)
			(end 0.12065 -0.305054)
			(stroke
				(width 0.1)
				(type default)
			)
			(layer "B.Fab")
		)
		(fp_line
			(start 0.67945 0.3048)
			(end 0.67945 -0.305054)
			(stroke
				(width 0.1)
				(type default)
			)
			(layer "B.Fab")
		)
		(pad "1" smd circle
			(at 0.40005 0 180)
			(size 0 0)
			(layers "B.Cu" "B.Mask" "B.Paste")
			(net "P3V3")
		)
		(pad "2" smd circle
			(at -0.40005 0 180)
			(size 0 0)
			(layers "B.Cu" "B.Mask" "B.Paste")
			(net "PU_9ZXL0451E_S3_HBW")
		)
	)
	(footprint ""
		(layer "B.Cu")
		(at 452.08444 -290.530788)
		(property "Reference" "PC1000"
			(at 0 0 0)
			(layer "B.SilkS")
			(hide yes)
			(effects
				(font
					(size 1.27 1.27)
				)
				(justify mirror)
			)
		)
		(property "Value" ""
			(at 0 0 0)
			(layer "B.Fab")
			(effects
				(font
					(size 1.27 1.27)
				)
				(justify mirror)
			)
		)
		(duplicate_pad_numbers_are_jumpers no)
		(fp_line
			(start -1.524 -0.762)
			(end -1.524 0.762)
			(stroke
				(width 0.1524)
				(type default)
			)
			(layer "B.SilkS")
		)
		(fp_line
			(start -1.524 0.762)
			(end 1.524 0.762)
			(stroke
				(width 0.1524)
				(type default)
			)
			(layer "B.SilkS")
		)
		(fp_line
			(start 1.524 -0.762)
			(end -1.524 -0.762)
			(stroke
				(width 0.1524)
				(type default)
			)
			(layer "B.SilkS")
		)
		(fp_line
			(start 1.524 0.762)
			(end 1.524 -0.762)
			(stroke
				(width 0.1524)
				(type default)
			)
			(layer "B.SilkS")
		)
		(fp_line
			(start -1.1049 -0.724916)
			(end 1.1049 -0.724916)
			(stroke
				(width 0.1)
				(type default)
			)
			(layer "B.Fab")
		)
		(fp_line
			(start -1.1049 0.724916)
			(end -1.1049 -0.724916)
			(stroke
				(width 0.1)
				(type default)
			)
			(layer "B.Fab")
		)
		(fp_line
			(start 1.1049 -0.724916)
			(end 1.1049 0.724916)
			(stroke
				(width 0.1)
				(type default)
			)
			(layer "B.Fab")
		)
		(fp_line
			(start 1.1049 0.724916)
			(end -1.1049 0.724916)
			(stroke
				(width 0.1)
				(type default)
			)
			(layer "B.Fab")
		)
		(pad "1" smd rect
			(at 0.889 0)
			(size 1.016 1.27)
			(layers "B.Cu" "B.Mask" "B.Paste")
			(net "P1V25_PEX3_R")
		)
		(pad "2" smd rect
			(at -0.889 0)
			(size 1.016 1.27)
			(layers "B.Cu" "B.Mask" "B.Paste")
			(net "GND")
		)
	)
	(footprint ""
		(layer "B.Cu")
		(at 61.597286 -110.497366)
		(property "Reference" "R84"
			(at 0 0 0)
			(layer "B.SilkS")
			(hide yes)
			(effects
				(font
					(size 1.27 1.27)
				)
				(justify mirror)
			)
		)
		(property "Value" ""
			(at 0 0 0)
			(layer "B.Fab")
			(effects
				(font
					(size 1.27 1.27)
				)
				(justify mirror)
			)
		)
		(duplicate_pad_numbers_are_jumpers no)
		(fp_line
			(start -0.7874 -0.4064)
			(end -0.7874 0.4064)
			(stroke
				(width 0.1524)
				(type default)
			)
			(layer "B.SilkS")
		)
		(fp_line
			(start -0.7874 0.4064)
			(end 0.7874 0.4064)
			(stroke
				(width 0.1524)
				(type default)
			)
			(layer "B.SilkS")
		)
		(fp_line
			(start 0.7874 -0.4064)
			(end -0.7874 -0.4064)
			(stroke
				(width 0.1524)
				(type default)
			)
			(layer "B.SilkS")
		)
		(fp_line
			(start 0.7874 0.4064)
			(end 0.7874 -0.4064)
			(stroke
				(width 0.1524)
				(type default)
			)
			(layer "B.SilkS")
		)
		(fp_line
			(start -0.67945 -0.3048)
			(end -0.67945 0.3048)
			(stroke
				(width 0.1)
				(type default)
			)
			(layer "B.Fab")
		)
		(fp_line
			(start -0.67945 0.3048)
			(end -0.120396 0.3048)
			(stroke
				(width 0.1)
				(type default)
			)
			(layer "B.Fab")
		)
		(fp_line
			(start -0.12065 -0.3048)
			(end -0.67945 -0.3048)
			(stroke
				(width 0.1)
				(type default)
			)
			(layer "B.Fab")
		)
		(fp_line
			(start -0.12065 -0.2794)
			(end -0.12065 -0.3048)
			(stroke
				(width 0.1)
				(type default)
			)
			(layer "B.Fab")
		)
		(fp_line
			(start -0.120396 0.2794)
			(end 0.12065 0.2794)
			(stroke
				(width 0.1)
				(type default)
			)
			(layer "B.Fab")
		)
		(fp_line
			(start -0.120396 0.3048)
			(end -0.120396 0.2794)
			(stroke
				(width 0.1)
				(type default)
			)
			(layer "B.Fab")
		)
		(fp_line
			(start 0.12065 -0.305054)
			(end 0.12065 -0.2794)
			(stroke
				(width 0.1)
				(type default)
			)
			(layer "B.Fab")
		)
		(fp_line
			(start 0.12065 -0.2794)
			(end -0.12065 -0.2794)
			(stroke
				(width 0.1)
				(type default)
			)
			(layer "B.Fab")
		)
		(fp_line
			(start 0.12065 0.2794)
			(end 0.12065 0.3048)
			(stroke
				(width 0.1)
				(type default)
			)
			(layer "B.Fab")
		)
		(fp_line
			(start 0.12065 0.3048)
			(end 0.67945 0.3048)
			(stroke
				(width 0.1)
				(type default)
			)
			(layer "B.Fab")
		)
		(fp_line
			(start 0.67945 -0.305054)
			(end 0.12065 -0.305054)
			(stroke
				(width 0.1)
				(type default)
			)
			(layer "B.Fab")
		)
		(fp_line
			(start 0.67945 0.3048)
			(end 0.67945 -0.305054)
			(stroke
				(width 0.1)
				(type default)
			)
			(layer "B.Fab")
		)
		(pad "1" smd circle
			(at 0.40005 0 180)
			(size 0 0)
			(layers "B.Cu" "B.Mask" "B.Paste")
			(net "NIC1_BIF2_N")
		)
		(pad "2" smd circle
			(at -0.40005 0 180)
			(size 0 0)
			(layers "B.Cu" "B.Mask" "B.Paste")
			(net "P3V3_AUX")
		)
	)
	(footprint ""
		(layer "B.Cu")
		(at 278.935942 -298.27474)
		(property "Reference" "C3416"
			(at 0 0 0)
			(layer "B.SilkS")
			(hide yes)
			(effects
				(font
					(size 1.27 1.27)
				)
				(justify mirror)
			)
		)
		(property "Value" ""
			(at 0 0 0)
			(layer "B.Fab")
			(effects
				(font
					(size 1.27 1.27)
				)
				(justify mirror)
			)
		)
		(duplicate_pad_numbers_are_jumpers no)
		(fp_line
			(start -0.299974 -0.150114)
			(end -0.299974 0.150114)
			(stroke
				(width 0.1)
				(type default)
			)
			(layer "B.Fab")
		)
		(fp_line
			(start -0.299974 0.150114)
			(end 0.299974 0.150114)
			(stroke
				(width 0.1)
				(type default)
			)
			(layer "B.Fab")
		)
		(fp_line
			(start 0.299974 -0.150114)
			(end -0.299974 -0.150114)
			(stroke
				(width 0.1)
				(type default)
			)
			(layer "B.Fab")
		)
		(fp_line
			(start 0.299974 0.150114)
			(end 0.299974 -0.150114)
			(stroke
				(width 0.1)
				(type default)
			)
			(layer "B.Fab")
		)
		(pad "1" smd rect
			(at 0.2667 0 180)
			(size 0.3048 0.381)
			(layers "B.Cu" "B.Mask" "B.Paste")
			(net "SYSPLL_VDDA18_PEX2")
		)
		(pad "2" smd rect
			(at -0.2667 0 180)
			(size 0.3048 0.381)
			(layers "B.Cu" "B.Mask" "B.Paste")
			(net "GND")
		)
	)
	(footprint ""
		(layer "B.Cu")
		(at 412.699962 -301.599854 -90)
		(property "Reference" "C1993"
			(at 0 0 90)
			(layer "B.SilkS")
			(hide yes)
			(effects
				(font
					(size 1.27 1.27)
				)
				(justify mirror)
			)
		)
		(property "Value" ""
			(at 0 0 90)
			(layer "B.Fab")
			(effects
				(font
					(size 1.27 1.27)
				)
				(justify mirror)
			)
		)
		(duplicate_pad_numbers_are_jumpers no)
		(fp_line
			(start -0.299974 0.150114)
			(end 0.299974 0.150114)
			(stroke
				(width 0.1)
				(type default)
			)
			(layer "B.Fab")
		)
		(fp_line
			(start 0.299974 0.150114)
			(end 0.299974 -0.150114)
			(stroke
				(width 0.1)
				(type default)
			)
			(layer "B.Fab")
		)
		(fp_line
			(start -0.299974 -0.150114)
			(end -0.299974 0.150114)
			(stroke
				(width 0.1)
				(type default)
			)
			(layer "B.Fab")
		)
		(fp_line
			(start 0.299974 -0.150114)
			(end -0.299974 -0.150114)
			(stroke
				(width 0.1)
				(type default)
			)
			(layer "B.Fab")
		)
		(pad "1" smd rect
			(at 0.2667 0 90)
			(size 0.3048 0.381)
			(layers "B.Cu" "B.Mask" "B.Paste")
			(net "P0V8_SERDES_VDDA_PEX3")
		)
		(pad "2" smd rect
			(at -0.2667 0 90)
			(size 0.3048 0.381)
			(layers "B.Cu" "B.Mask" "B.Paste")
			(net "GND")
		)
	)
	(footprint ""
		(layer "B.Cu")
		(at 132.78231 -325.30923 -90)
		(property "Reference" "C4259"
			(at 0 0 90)
			(layer "B.SilkS")
			(hide yes)
			(effects
				(font
					(size 1.27 1.27)
				)
				(justify mirror)
			)
		)
		(property "Value" ""
			(at 0 0 90)
			(layer "B.Fab")
			(effects
				(font
					(size 1.27 1.27)
				)
				(justify mirror)
			)
		)
		(duplicate_pad_numbers_are_jumpers no)
		(fp_line
			(start -1.2954 0.5842)
			(end 1.2954 0.5842)
			(stroke
				(width 0.1524)
				(type default)
			)
			(layer "B.SilkS")
		)
		(fp_line
			(start 1.2954 0.5842)
			(end 1.2954 -0.5842)
			(stroke
				(width 0.1524)
				(type default)
			)
			(layer "B.SilkS")
		)
		(fp_line
			(start -1.2954 -0.5842)
			(end -1.2954 0.5842)
			(stroke
				(width 0.1524)
				(type default)
			)
			(layer "B.SilkS")
		)
		(fp_line
			(start 1.2954 -0.5842)
			(end -1.2954 -0.5842)
			(stroke
				(width 0.1524)
				(type default)
			)
			(layer "B.SilkS")
		)
		(fp_line
			(start -0.8636 0.4572)
			(end 0.8636 0.4572)
			(stroke
				(width 0.1)
				(type default)
			)
			(layer "B.Fab")
		)
		(fp_line
			(start 0.8636 0.4572)
			(end 0.8636 0.4064)
			(stroke
				(width 0.1)
				(type default)
			)
			(layer "B.Fab")
		)
		(fp_line
			(start -1.1938 0.4064)
			(end -0.8636 0.4064)
			(stroke
				(width 0.1)
				(type default)
			)
			(layer "B.Fab")
		)
		(fp_line
			(start -0.8636 0.4064)
			(end -0.8636 0.4572)
			(stroke
				(width 0.1)
				(type default)
			)
			(layer "B.Fab")
		)
		(fp_line
			(start 0.8636 0.4064)
			(end 1.1938 0.4064)
			(stroke
				(width 0.1)
				(type default)
			)
			(layer "B.Fab")
		)
		(fp_line
			(start 1.1938 0.4064)
			(end 1.1938 -0.4064)
			(stroke
				(width 0.1)
				(type default)
			)
			(layer "B.Fab")
		)
		(fp_line
			(start -1.1938 -0.4064)
			(end -1.1938 0.4064)
			(stroke
				(width 0.1)
				(type default)
			)
			(layer "B.Fab")
		)
		(fp_line
			(start -0.8636 -0.4064)
			(end -1.1938 -0.4064)
			(stroke
				(width 0.1)
				(type default)
			)
			(layer "B.Fab")
		)
		(fp_line
			(start 0.8636 -0.4064)
			(end 0.8636 -0.4572)
			(stroke
				(width 0.1)
				(type default)
			)
			(layer "B.Fab")
		)
		(fp_line
			(start 1.1938 -0.4064)
			(end 0.8636 -0.4064)
			(stroke
				(width 0.1)
				(type default)
			)
			(layer "B.Fab")
		)
		(fp_line
			(start -0.8636 -0.4572)
			(end -0.8636 -0.4064)
			(stroke
				(width 0.1)
				(type default)
			)
			(layer "B.Fab")
		)
		(fp_line
			(start 0.8636 -0.4572)
			(end -0.8636 -0.4572)
			(stroke
				(width 0.1)
				(type default)
			)
			(layer "B.Fab")
		)
		(pad "1" smd rect
			(at 0.7366 0 180)
			(size 0.7112 0.8128)
			(layers "B.Cu" "B.Mask" "B.Paste")
			(net "P0V8_SERDES_VDDA_PEX1_C5")
		)
		(pad "2" smd rect
			(at -0.7366 0 180)
			(size 0.7112 0.8128)
			(layers "B.Cu" "B.Mask" "B.Paste")
			(net "GND")
		)
	)
	(footprint ""
		(layer "B.Cu")
		(at 48.04156 -303.024794)
		(property "Reference" "C2995"
			(at 0 0 0)
			(layer "B.SilkS")
			(hide yes)
			(effects
				(font
					(size 1.27 1.27)
				)
				(justify mirror)
			)
		)
		(property "Value" ""
			(at 0 0 0)
			(layer "B.Fab")
			(effects
				(font
					(size 1.27 1.27)
				)
				(justify mirror)
			)
		)
		(duplicate_pad_numbers_are_jumpers no)
		(fp_line
			(start -0.299974 -0.150114)
			(end -0.299974 0.150114)
			(stroke
				(width 0.1)
				(type default)
			)
			(layer "B.Fab")
		)
		(fp_line
			(start -0.299974 0.150114)
			(end 0.299974 0.150114)
			(stroke
				(width 0.1)
				(type default)
			)
			(layer "B.Fab")
		)
		(fp_line
			(start 0.299974 -0.150114)
			(end -0.299974 -0.150114)
			(stroke
				(width 0.1)
				(type default)
			)
			(layer "B.Fab")
		)
		(fp_line
			(start 0.299974 0.150114)
			(end 0.299974 -0.150114)
			(stroke
				(width 0.1)
				(type default)
			)
			(layer "B.Fab")
		)
		(pad "1" smd rect
			(at 0.2667 0 180)
			(size 0.3048 0.381)
			(layers "B.Cu" "B.Mask" "B.Paste")
			(net "P1V8_VDDA_PEX0")
		)
		(pad "2" smd rect
			(at -0.2667 0 180)
			(size 0.3048 0.381)
			(layers "B.Cu" "B.Mask" "B.Paste")
			(net "GND")
		)
	)
	(footprint ""
		(layer "B.Cu")
		(at 302.303942 -97.663)
		(property "Reference" "R259"
			(at 0 0 0)
			(layer "B.SilkS")
			(hide yes)
			(effects
				(font
					(size 1.27 1.27)
				)
				(justify mirror)
			)
		)
		(property "Value" ""
			(at 0 0 0)
			(layer "B.Fab")
			(effects
				(font
					(size 1.27 1.27)
				)
				(justify mirror)
			)
		)
		(duplicate_pad_numbers_are_jumpers no)
		(fp_line
			(start -0.7874 -0.4064)
			(end -0.7874 0.4064)
			(stroke
				(width 0.1524)
				(type default)
			)
			(layer "B.SilkS")
		)
		(fp_line
			(start -0.7874 0.4064)
			(end 0.7874 0.4064)
			(stroke
				(width 0.1524)
				(type default)
			)
			(layer "B.SilkS")
		)
		(fp_line
			(start 0.7874 -0.4064)
			(end -0.7874 -0.4064)
			(stroke
				(width 0.1524)
				(type default)
			)
			(layer "B.SilkS")
		)
		(fp_line
			(start 0.7874 0.4064)
			(end 0.7874 -0.4064)
			(stroke
				(width 0.1524)
				(type default)
			)
			(layer "B.SilkS")
		)
		(fp_line
			(start -0.67945 -0.3048)
			(end -0.67945 0.3048)
			(stroke
				(width 0.1)
				(type default)
			)
			(layer "B.Fab")
		)
		(fp_line
			(start -0.67945 0.3048)
			(end -0.120396 0.3048)
			(stroke
				(width 0.1)
				(type default)
			)
			(layer "B.Fab")
		)
		(fp_line
			(start -0.12065 -0.3048)
			(end -0.67945 -0.3048)
			(stroke
				(width 0.1)
				(type default)
			)
			(layer "B.Fab")
		)
		(fp_line
			(start -0.12065 -0.2794)
			(end -0.12065 -0.3048)
			(stroke
				(width 0.1)
				(type default)
			)
			(layer "B.Fab")
		)
		(fp_line
			(start -0.120396 0.2794)
			(end 0.12065 0.2794)
			(stroke
				(width 0.1)
				(type default)
			)
			(layer "B.Fab")
		)
		(fp_line
			(start -0.120396 0.3048)
			(end -0.120396 0.2794)
			(stroke
				(width 0.1)
				(type default)
			)
			(layer "B.Fab")
		)
		(fp_line
			(start 0.12065 -0.305054)
			(end 0.12065 -0.2794)
			(stroke
				(width 0.1)
				(type default)
			)
			(layer "B.Fab")
		)
		(fp_line
			(start 0.12065 -0.2794)
			(end -0.12065 -0.2794)
			(stroke
				(width 0.1)
				(type default)
			)
			(layer "B.Fab")
		)
		(fp_line
			(start 0.12065 0.2794)
			(end 0.12065 0.3048)
			(stroke
				(width 0.1)
				(type default)
			)
			(layer "B.Fab")
		)
		(fp_line
			(start 0.12065 0.3048)
			(end 0.67945 0.3048)
			(stroke
				(width 0.1)
				(type default)
			)
			(layer "B.Fab")
		)
		(fp_line
			(start 0.67945 -0.305054)
			(end 0.12065 -0.305054)
			(stroke
				(width 0.1)
				(type default)
			)
			(layer "B.Fab")
		)
		(fp_line
			(start 0.67945 0.3048)
			(end 0.67945 -0.305054)
			(stroke
				(width 0.1)
				(type default)
			)
			(layer "B.Fab")
		)
		(pad "1" smd circle
			(at 0.40005 0 180)
			(size 0 0)
			(layers "B.Cu" "B.Mask" "B.Paste")
			(net "PWRGD_NIC5_PWR_GOOD")
		)
		(pad "2" smd circle
			(at -0.40005 0 180)
			(size 0 0)
			(layers "B.Cu" "B.Mask" "B.Paste")
			(net "PWRGD_NIC5_PWR_GOOD_R")
		)
	)
)
